(kicad_pcb
	(version 20260206)
	(generator "pcbnew")
	(generator_version "10.0")
	(general
		(thickness 1.6)
		(legacy_teardrops no)
	)
	(paper "A4")
	(title_block
		(title "9054_F0T_PDB_BD_GPU_F_V04_1213_1550_OCP.brd")
		(comment 1 "Grand Teton / footprints 354-361 of 608")
	)
	(layers
		(0 "F.Cu" signal "TOP")
		(4 "In1.Cu" signal "GND")
		(6 "In2.Cu" signal "IN1")
		(8 "In3.Cu" signal "GND1")
		(10 "In4.Cu" signal "VCC")
		(12 "In5.Cu" signal "VCC1")
		(14 "In6.Cu" signal "GND2")
		(16 "In7.Cu" signal "IN2")
		(18 "In8.Cu" signal "GND3")
		(2 "B.Cu" signal "BOTTOM")
		(9 "F.Adhes" user "F.Adhesive")
		(11 "B.Adhes" user "B.Adhesive")
		(13 "F.Paste" user "Package Geometry/Pastemask Top")
		(15 "B.Paste" user "Package Geometry/Pastemask Bottom")
		(5 "F.SilkS" user "Ref Des/Silkscreen Top")
		(7 "B.SilkS" user "Ref Des/Silkscreen Bottom")
		(1 "F.Mask" user "Board Geometry/Soldermask Top")
		(3 "B.Mask" user "Board Geometry/Soldermask Bottom")
		(17 "Dwgs.User" user "User.Drawings")
		(19 "Cmts.User" user "User.Comments")
		(21 "Eco1.User" user "User.Eco1")
		(23 "Eco2.User" user "User.Eco2")
		(25 "Edge.Cuts" user "Board Geometry/Outline")
		(27 "Margin" user)
		(31 "F.CrtYd" user "Package Geometry/Place Bound Top")
		(29 "B.CrtYd" user "Package Geometry/Place Bound Bottom")
		(35 "F.Fab" user "Ref Des/Assembly Top")
		(33 "B.Fab" user "Ref Des/Assembly Bottom")
	)
	(footprint ""
		(layer "F.Cu")
		(at 438.3278 -23.749 180)
		(property "Reference" "R65"
			(at 0 0 180)
			(layer "F.SilkS")
			(hide yes)
			(effects
				(font
					(size 1.27 1.27)
				)
			)
		)
		(property "Value" ""
			(at 0 0 180)
			(layer "F.Fab")
			(effects
				(font
					(size 1.27 1.27)
				)
			)
		)
		(duplicate_pad_numbers_are_jumpers no)
		(fp_line
			(start 0.7874 0.4064)
			(end -0.7874 0.4064)
			(stroke
				(width 0.1524)
				(type default)
			)
			(layer "F.SilkS")
		)
		(fp_line
			(start 0.7874 -0.4064)
			(end 0.7874 0.4064)
			(stroke
				(width 0.1524)
				(type default)
			)
			(layer "F.SilkS")
		)
		(fp_line
			(start -0.7874 0.4064)
			(end -0.7874 -0.4064)
			(stroke
				(width 0.1524)
				(type default)
			)
			(layer "F.SilkS")
		)
		(fp_line
			(start -0.7874 -0.4064)
			(end 0.7874 -0.4064)
			(stroke
				(width 0.1524)
				(type default)
			)
			(layer "F.SilkS")
		)
		(fp_line
			(start 0.67945 0.3048)
			(end 0.120396 0.3048)
			(stroke
				(width 0.1)
				(type default)
			)
			(layer "F.Fab")
		)
		(fp_line
			(start 0.67945 -0.3048)
			(end 0.67945 0.3048)
			(stroke
				(width 0.1)
				(type default)
			)
			(layer "F.Fab")
		)
		(fp_line
			(start 0.12065 -0.2794)
			(end 0.12065 -0.3048)
			(stroke
				(width 0.1)
				(type default)
			)
			(layer "F.Fab")
		)
		(fp_line
			(start 0.12065 -0.3048)
			(end 0.67945 -0.3048)
			(stroke
				(width 0.1)
				(type default)
			)
			(layer "F.Fab")
		)
		(fp_line
			(start 0.120396 0.3048)
			(end 0.120396 0.2794)
			(stroke
				(width 0.1)
				(type default)
			)
			(layer "F.Fab")
		)
		(fp_line
			(start 0.120396 0.2794)
			(end -0.12065 0.2794)
			(stroke
				(width 0.1)
				(type default)
			)
			(layer "F.Fab")
		)
		(fp_line
			(start -0.12065 0.3048)
			(end -0.67945 0.3048)
			(stroke
				(width 0.1)
				(type default)
			)
			(layer "F.Fab")
		)
		(fp_line
			(start -0.12065 0.2794)
			(end -0.12065 0.3048)
			(stroke
				(width 0.1)
				(type default)
			)
			(layer "F.Fab")
		)
		(fp_line
			(start -0.12065 -0.2794)
			(end 0.12065 -0.2794)
			(stroke
				(width 0.1)
				(type default)
			)
			(layer "F.Fab")
		)
		(fp_line
			(start -0.12065 -0.305054)
			(end -0.12065 -0.2794)
			(stroke
				(width 0.1)
				(type default)
			)
			(layer "F.Fab")
		)
		(fp_line
			(start -0.67945 0.3048)
			(end -0.67945 -0.305054)
			(stroke
				(width 0.1)
				(type default)
			)
			(layer "F.Fab")
		)
		(fp_line
			(start -0.67945 -0.305054)
			(end -0.12065 -0.305054)
			(stroke
				(width 0.1)
				(type default)
			)
			(layer "F.Fab")
		)
		(pad "1" smd circle
			(at -0.40005 0 180)
			(size 0 0)
			(layers "F.Cu" "F.Mask" "F.Paste")
			(net "GND")
		)
		(pad "2" smd circle
			(at 0.40005 0 180)
			(size 0 0)
			(layers "F.Cu" "F.Mask" "F.Paste")
			(net "FRU_ADDR1")
		)
	)
	(footprint ""
		(layer "F.Cu")
		(at 160.274 -80.645 -90)
		(property "Reference" "R5906"
			(at 0 0 270)
			(layer "F.SilkS")
			(hide yes)
			(effects
				(font
					(size 1.27 1.27)
				)
			)
		)
		(property "Value" ""
			(at 0 0 270)
			(layer "F.Fab")
			(effects
				(font
					(size 1.27 1.27)
				)
			)
		)
		(duplicate_pad_numbers_are_jumpers no)
		(fp_line
			(start -1.651 0.8382)
			(end -1.651 -0.8382)
			(stroke
				(width 0.1524)
				(type default)
			)
			(layer "F.SilkS")
		)
		(fp_line
			(start 1.651 0.8382)
			(end -1.651 0.8382)
			(stroke
				(width 0.1524)
				(type default)
			)
			(layer "F.SilkS")
		)
		(fp_line
			(start -1.651 -0.8382)
			(end 1.651 -0.8382)
			(stroke
				(width 0.1524)
				(type default)
			)
			(layer "F.SilkS")
		)
		(fp_line
			(start 1.651 -0.8382)
			(end 1.651 0.8382)
			(stroke
				(width 0.1524)
				(type default)
			)
			(layer "F.SilkS")
		)
		(fp_line
			(start -1.559814 0.7366)
			(end -1.524 0.7366)
			(stroke
				(width 0.1)
				(type default)
			)
			(layer "F.Fab")
		)
		(fp_line
			(start -1.524 0.7366)
			(end 1.524 0.7366)
			(stroke
				(width 0.1)
				(type default)
			)
			(layer "F.Fab")
		)
		(fp_line
			(start 1.524 0.7366)
			(end 1.560576 0.7366)
			(stroke
				(width 0.1)
				(type default)
			)
			(layer "F.Fab")
		)
		(fp_line
			(start 1.560576 0.7366)
			(end 1.560576 -0.7366)
			(stroke
				(width 0.1)
				(type default)
			)
			(layer "F.Fab")
		)
		(fp_line
			(start -1.559814 -0.7366)
			(end -1.559814 0.7366)
			(stroke
				(width 0.1)
				(type default)
			)
			(layer "F.Fab")
		)
		(fp_line
			(start -1.524 -0.7366)
			(end -1.559814 -0.7366)
			(stroke
				(width 0.1)
				(type default)
			)
			(layer "F.Fab")
		)
		(fp_line
			(start 1.524 -0.7366)
			(end -1.524 -0.7366)
			(stroke
				(width 0.1)
				(type default)
			)
			(layer "F.Fab")
		)
		(fp_line
			(start 1.560576 -0.7366)
			(end 1.524 -0.7366)
			(stroke
				(width 0.1)
				(type default)
			)
			(layer "F.Fab")
		)
		(pad "1" smd rect
			(at -0.94996 0 90)
			(size 1.1176 1.3716)
			(layers "F.Cu" "F.Mask" "F.Paste")
			(net "P52V_2_BUSBAR")
		)
		(pad "2" smd rect
			(at 0.94996 0 90)
			(size 1.1176 1.3716)
			(layers "F.Cu" "F.Mask" "F.Paste")
			(net "FM_HS2_EN_BUSBAR")
		)
	)
	(footprint ""
		(layer "F.Cu")
		(at 33.85439 -36.957 180)
		(property "Reference" "R43"
			(at 0 0 180)
			(layer "F.SilkS")
			(hide yes)
			(effects
				(font
					(size 1.27 1.27)
				)
			)
		)
		(property "Value" ""
			(at 0 0 180)
			(layer "F.Fab")
			(effects
				(font
					(size 1.27 1.27)
				)
			)
		)
		(duplicate_pad_numbers_are_jumpers no)
		(fp_line
			(start 2.234946 0.9271)
			(end -2.234946 0.9271)
			(stroke
				(width 0.1524)
				(type default)
			)
			(layer "F.SilkS")
		)
		(fp_line
			(start 2.234946 -0.9271)
			(end 2.234946 0.9271)
			(stroke
				(width 0.1524)
				(type default)
			)
			(layer "F.SilkS")
		)
		(fp_line
			(start -2.234946 0.9271)
			(end -2.234946 -0.9271)
			(stroke
				(width 0.1524)
				(type default)
			)
			(layer "F.SilkS")
		)
		(fp_line
			(start -2.234946 -0.9271)
			(end 2.234946 -0.9271)
			(stroke
				(width 0.1524)
				(type default)
			)
			(layer "F.SilkS")
		)
		(fp_line
			(start 1.575054 0.824992)
			(end 1.575054 -0.824992)
			(stroke
				(width 0.1)
				(type default)
			)
			(layer "F.Fab")
		)
		(fp_line
			(start 1.575054 -0.824992)
			(end -1.575054 -0.824992)
			(stroke
				(width 0.1)
				(type default)
			)
			(layer "F.Fab")
		)
		(fp_line
			(start -1.575054 0.824992)
			(end 1.575054 0.824992)
			(stroke
				(width 0.1)
				(type default)
			)
			(layer "F.Fab")
		)
		(fp_line
			(start -1.575054 -0.824992)
			(end -1.575054 0.824992)
			(stroke
				(width 0.1)
				(type default)
			)
			(layer "F.Fab")
		)
		(pad "1" smd rect
			(at -1.599946 0 180)
			(size 1.016 1.6002)
			(layers "F.Cu" "F.Mask" "F.Paste")
			(net "LED_D2_R2")
		)
		(pad "2" smd rect
			(at 1.599946 0 180)
			(size 1.016 1.6002)
			(layers "F.Cu" "F.Mask" "F.Paste")
			(net "LED_D2_R3")
		)
	)
	(footprint ""
		(layer "F.Cu")
		(at 449.834 -50.927)
		(property "Reference" "R5914"
			(at 0 0 0)
			(layer "F.SilkS")
			(hide yes)
			(effects
				(font
					(size 1.27 1.27)
				)
			)
		)
		(property "Value" ""
			(at 0 0 0)
			(layer "F.Fab")
			(effects
				(font
					(size 1.27 1.27)
				)
			)
		)
		(duplicate_pad_numbers_are_jumpers no)
		(fp_line
			(start -0.7874 -0.4064)
			(end 0.7874 -0.4064)
			(stroke
				(width 0.1524)
				(type default)
			)
			(layer "F.SilkS")
		)
		(fp_line
			(start -0.7874 0.4064)
			(end -0.7874 -0.4064)
			(stroke
				(width 0.1524)
				(type default)
			)
			(layer "F.SilkS")
		)
		(fp_line
			(start 0.7874 -0.4064)
			(end 0.7874 0.4064)
			(stroke
				(width 0.1524)
				(type default)
			)
			(layer "F.SilkS")
		)
		(fp_line
			(start 0.7874 0.4064)
			(end -0.7874 0.4064)
			(stroke
				(width 0.1524)
				(type default)
			)
			(layer "F.SilkS")
		)
		(fp_line
			(start -0.67945 -0.305054)
			(end -0.12065 -0.305054)
			(stroke
				(width 0.1)
				(type default)
			)
			(layer "F.Fab")
		)
		(fp_line
			(start -0.67945 0.3048)
			(end -0.67945 -0.305054)
			(stroke
				(width 0.1)
				(type default)
			)
			(layer "F.Fab")
		)
		(fp_line
			(start -0.12065 -0.305054)
			(end -0.12065 -0.2794)
			(stroke
				(width 0.1)
				(type default)
			)
			(layer "F.Fab")
		)
		(fp_line
			(start -0.12065 -0.2794)
			(end 0.12065 -0.2794)
			(stroke
				(width 0.1)
				(type default)
			)
			(layer "F.Fab")
		)
		(fp_line
			(start -0.12065 0.2794)
			(end -0.12065 0.3048)
			(stroke
				(width 0.1)
				(type default)
			)
			(layer "F.Fab")
		)
		(fp_line
			(start -0.12065 0.3048)
			(end -0.67945 0.3048)
			(stroke
				(width 0.1)
				(type default)
			)
			(layer "F.Fab")
		)
		(fp_line
			(start 0.120396 0.2794)
			(end -0.12065 0.2794)
			(stroke
				(width 0.1)
				(type default)
			)
			(layer "F.Fab")
		)
		(fp_line
			(start 0.120396 0.3048)
			(end 0.120396 0.2794)
			(stroke
				(width 0.1)
				(type default)
			)
			(layer "F.Fab")
		)
		(fp_line
			(start 0.12065 -0.3048)
			(end 0.67945 -0.3048)
			(stroke
				(width 0.1)
				(type default)
			)
			(layer "F.Fab")
		)
		(fp_line
			(start 0.12065 -0.2794)
			(end 0.12065 -0.3048)
			(stroke
				(width 0.1)
				(type default)
			)
			(layer "F.Fab")
		)
		(fp_line
			(start 0.67945 -0.3048)
			(end 0.67945 0.3048)
			(stroke
				(width 0.1)
				(type default)
			)
			(layer "F.Fab")
		)
		(fp_line
			(start 0.67945 0.3048)
			(end 0.120396 0.3048)
			(stroke
				(width 0.1)
				(type default)
			)
			(layer "F.Fab")
		)
		(pad "1" smd circle
			(at -0.40005 0)
			(size 0 0)
			(layers "F.Cu" "F.Mask" "F.Paste")
			(net "P3V3_AUX")
		)
		(pad "2" smd circle
			(at 0.40005 0)
			(size 0 0)
			(layers "F.Cu" "F.Mask" "F.Paste")
			(net "PWRGD_P3V3_HPDB_R")
		)
	)
	(footprint ""
		(layer "F.Cu")
		(at 61.92139 -139.7)
		(property "Reference" "PC35"
			(at -8.93699 -4.41833 0)
			(unlocked yes)
			(layer "F.SilkS")
			(effects
				(font
					(size 0.7874 0.5842)
					(thickness 0.1524)
				)
				(justify left)
			)
		)
		(property "Value" ""
			(at 0 0 0)
			(layer "F.Fab")
			(effects
				(font
					(size 1.27 1.27)
				)
			)
		)
		(duplicate_pad_numbers_are_jumpers no)
		(fp_line
			(start -9.253728 3.750056)
			(end 9.249918 3.750056)
			(stroke
				(width 0.1524)
				(type default)
			)
			(layer "F.SilkS")
		)
		(fp_line
			(start 0 3.750056)
			(end -9.253728 3.750056)
			(stroke
				(width 0.1524)
				(type default)
			)
			(layer "F.SilkS")
		)
		(fp_circle
			(center 0 3.750056)
			(end 9.249918 3.750056)
			(stroke
				(width 0.1524)
				(type default)
			)
			(fill no)
			(layer "F.SilkS")
		)
		(fp_poly
			(pts
				(arc
					(start 9.249918 3.750056)
					(mid 0 12.999974)
					(end -9.249918 3.750056)
				)
			)
			(stroke
				(width 0)
				(type default)
			)
			(fill yes)
			(layer "F.SilkS")
		)
		(fp_circle
			(center 0 3.750056)
			(end 9.249918 3.750056)
			(stroke
				(width 0.1)
				(type default)
			)
			(fill no)
			(layer "F.Fab")
		)
		(pad "1" thru_hole rect
			(at 0 0)
			(size 1.778 1.778)
			(drill 1.27)
			(layers "*.Cu" "*.Mask")
			(remove_unused_layers no)
			(net "P52V_HS2")
			(clearance 0)
			(padstack
				(mode front_inner_back)
				(layer "Inner"
					(shape circle)
					(size 1.778 1.778)
					(clearance 0)
				)
				(layer "B.Cu"
					(shape rect)
					(size 1.778 1.778)
					(clearance 0)
				)
			)
		)
		(pad "2" thru_hole circle
			(at 0 7.500112)
			(size 1.778 1.778)
			(drill 1.27)
			(layers "*.Cu" "*.Mask")
			(remove_unused_layers no)
			(net "GND")
			(clearance 0)
		)
	)
	(footprint ""
		(layer "F.Cu")
		(at 61.92139 -78.74)
		(property "Reference" "PC45"
			(at -8.42899 -5.30733 0)
			(unlocked yes)
			(layer "F.SilkS")
			(effects
				(font
					(size 0.7874 0.5842)
					(thickness 0.1524)
				)
				(justify left)
			)
		)
		(property "Value" ""
			(at 0 0 0)
			(layer "F.Fab")
			(effects
				(font
					(size 1.27 1.27)
				)
			)
		)
		(duplicate_pad_numbers_are_jumpers no)
		(fp_line
			(start -9.253728 3.750056)
			(end 9.249918 3.750056)
			(stroke
				(width 0.1524)
				(type default)
			)
			(layer "F.SilkS")
		)
		(fp_line
			(start 0 3.750056)
			(end -9.253728 3.750056)
			(stroke
				(width 0.1524)
				(type default)
			)
			(layer "F.SilkS")
		)
		(fp_circle
			(center 0 3.750056)
			(end 9.249918 3.750056)
			(stroke
				(width 0.1524)
				(type default)
			)
			(fill no)
			(layer "F.SilkS")
		)
		(fp_poly
			(pts
				(arc
					(start 9.249918 3.750056)
					(mid 0 12.999974)
					(end -9.249918 3.750056)
				)
			)
			(stroke
				(width 0)
				(type default)
			)
			(fill yes)
			(layer "F.SilkS")
		)
		(fp_circle
			(center 0 3.750056)
			(end 9.249918 3.750056)
			(stroke
				(width 0.1)
				(type default)
			)
			(fill no)
			(layer "F.Fab")
		)
		(pad "1" thru_hole rect
			(at 0 0)
			(size 1.778 1.778)
			(drill 1.27)
			(layers "*.Cu" "*.Mask")
			(remove_unused_layers no)
			(net "P52V_HS2")
			(clearance 0)
			(padstack
				(mode front_inner_back)
				(layer "Inner"
					(shape circle)
					(size 1.778 1.778)
					(clearance 0)
				)
				(layer "B.Cu"
					(shape rect)
					(size 1.778 1.778)
					(clearance 0)
				)
			)
		)
		(pad "2" thru_hole circle
			(at 0 7.500112)
			(size 1.778 1.778)
			(drill 1.27)
			(layers "*.Cu" "*.Mask")
			(remove_unused_layers no)
			(net "GND")
			(clearance 0)
		)
	)
	(footprint ""
		(layer "F.Cu")
		(at 99.2632 -14.097 180)
		(property "Reference" "R162"
			(at 0 0 180)
			(layer "F.SilkS")
			(hide yes)
			(effects
				(font
					(size 1.27 1.27)
				)
			)
		)
		(property "Value" ""
			(at 0 0 180)
			(layer "F.Fab")
			(effects
				(font
					(size 1.27 1.27)
				)
			)
		)
		(duplicate_pad_numbers_are_jumpers no)
		(fp_line
			(start 1.651 0.8382)
			(end -1.651 0.8382)
			(stroke
				(width 0.1524)
				(type default)
			)
			(layer "F.SilkS")
		)
		(fp_line
			(start 1.651 -0.8382)
			(end 1.651 0.8382)
			(stroke
				(width 0.1524)
				(type default)
			)
			(layer "F.SilkS")
		)
		(fp_line
			(start -1.651 0.8382)
			(end -1.651 -0.8382)
			(stroke
				(width 0.1524)
				(type default)
			)
			(layer "F.SilkS")
		)
		(fp_line
			(start -1.651 -0.8382)
			(end 1.651 -0.8382)
			(stroke
				(width 0.1524)
				(type default)
			)
			(layer "F.SilkS")
		)
		(fp_line
			(start 1.560576 0.7366)
			(end 1.560576 -0.7366)
			(stroke
				(width 0.1)
				(type default)
			)
			(layer "F.Fab")
		)
		(fp_line
			(start 1.560576 -0.7366)
			(end 1.524 -0.7366)
			(stroke
				(width 0.1)
				(type default)
			)
			(layer "F.Fab")
		)
		(fp_line
			(start 1.524 0.7366)
			(end 1.560576 0.7366)
			(stroke
				(width 0.1)
				(type default)
			)
			(layer "F.Fab")
		)
		(fp_line
			(start 1.524 -0.7366)
			(end -1.524 -0.7366)
			(stroke
				(width 0.1)
				(type default)
			)
			(layer "F.Fab")
		)
		(fp_line
			(start -1.524 0.7366)
			(end 1.524 0.7366)
			(stroke
				(width 0.1)
				(type default)
			)
			(layer "F.Fab")
		)
		(fp_line
			(start -1.524 -0.7366)
			(end -1.559814 -0.7366)
			(stroke
				(width 0.1)
				(type default)
			)
			(layer "F.Fab")
		)
		(fp_line
			(start -1.559814 0.7366)
			(end -1.524 0.7366)
			(stroke
				(width 0.1)
				(type default)
			)
			(layer "F.Fab")
		)
		(fp_line
			(start -1.559814 -0.7366)
			(end -1.559814 0.7366)
			(stroke
				(width 0.1)
				(type default)
			)
			(layer "F.Fab")
		)
		(pad "1" smd rect
			(at -0.94996 0)
			(size 1.1176 1.3716)
			(layers "F.Cu" "F.Mask" "F.Paste")
			(net "P52V_HS2")
		)
		(pad "2" smd rect
			(at 0.94996 0)
			(size 1.1176 1.3716)
			(layers "F.Cu" "F.Mask" "F.Paste")
			(net "PWRGD_P52V_HS2_4287_PG_R_N")
		)
	)
	(footprint ""
		(layer "F.Cu")
		(at 450.4436 -90.5002 180)
		(property "Reference" "PR110"
			(at 0 0 180)
			(layer "F.SilkS")
			(hide yes)
			(effects
				(font
					(size 1.27 1.27)
				)
			)
		)
		(property "Value" ""
			(at 0 0 180)
			(layer "F.Fab")
			(effects
				(font
					(size 1.27 1.27)
				)
			)
		)
		(duplicate_pad_numbers_are_jumpers no)
		(fp_line
			(start 0.7874 0.4064)
			(end -0.7874 0.4064)
			(stroke
				(width 0.1524)
				(type default)
			)
			(layer "F.SilkS")
		)
		(fp_line
			(start 0.7874 -0.4064)
			(end 0.7874 0.4064)
			(stroke
				(width 0.1524)
				(type default)
			)
			(layer "F.SilkS")
		)
		(fp_line
			(start -0.7874 0.4064)
			(end -0.7874 -0.4064)
			(stroke
				(width 0.1524)
				(type default)
			)
			(layer "F.SilkS")
		)
		(fp_line
			(start -0.7874 -0.4064)
			(end 0.7874 -0.4064)
			(stroke
				(width 0.1524)
				(type default)
			)
			(layer "F.SilkS")
		)
		(fp_line
			(start 0.67945 0.3048)
			(end 0.120396 0.3048)
			(stroke
				(width 0.1)
				(type default)
			)
			(layer "F.Fab")
		)
		(fp_line
			(start 0.67945 -0.3048)
			(end 0.67945 0.3048)
			(stroke
				(width 0.1)
				(type default)
			)
			(layer "F.Fab")
		)
		(fp_line
			(start 0.12065 -0.2794)
			(end 0.12065 -0.3048)
			(stroke
				(width 0.1)
				(type default)
			)
			(layer "F.Fab")
		)
		(fp_line
			(start 0.12065 -0.3048)
			(end 0.67945 -0.3048)
			(stroke
				(width 0.1)
				(type default)
			)
			(layer "F.Fab")
		)
		(fp_line
			(start 0.120396 0.3048)
			(end 0.120396 0.2794)
			(stroke
				(width 0.1)
				(type default)
			)
			(layer "F.Fab")
		)
		(fp_line
			(start 0.120396 0.2794)
			(end -0.12065 0.2794)
			(stroke
				(width 0.1)
				(type default)
			)
			(layer "F.Fab")
		)
		(fp_line
			(start -0.12065 0.3048)
			(end -0.67945 0.3048)
			(stroke
				(width 0.1)
				(type default)
			)
			(layer "F.Fab")
		)
		(fp_line
			(start -0.12065 0.2794)
			(end -0.12065 0.3048)
			(stroke
				(width 0.1)
				(type default)
			)
			(layer "F.Fab")
		)
		(fp_line
			(start -0.12065 -0.2794)
			(end 0.12065 -0.2794)
			(stroke
				(width 0.1)
				(type default)
			)
			(layer "F.Fab")
		)
		(fp_line
			(start -0.12065 -0.305054)
			(end -0.12065 -0.2794)
			(stroke
				(width 0.1)
				(type default)
			)
			(layer "F.Fab")
		)
		(fp_line
			(start -0.67945 0.3048)
			(end -0.67945 -0.305054)
			(stroke
				(width 0.1)
				(type default)
			)
			(layer "F.Fab")
		)
		(fp_line
			(start -0.67945 -0.305054)
			(end -0.12065 -0.305054)
			(stroke
				(width 0.1)
				(type default)
			)
			(layer "F.Fab")
		)
		(pad "1" smd circle
			(at -0.40005 0 180)
			(size 0 0)
			(layers "F.Cu" "F.Mask" "F.Paste")
			(net "P3V3_AUX")
		)
		(pad "2" smd circle
			(at 0.40005 0 180)
			(size 0 0)
			(layers "F.Cu" "F.Mask" "F.Paste")
			(net "P3V3_HPDB_PG_R")
		)
	)
)
